# TIMECARD (Time Appliance Project (Time Card)) — schematic netlist excerpt (pin names and nets, part order shuffled) for the footprints in the layout excerpt that follows; sources: Cadence DE-HDL packaged netlist, KiCad conversion of R4006-B0001-02_R01.brd

U3  74LVC1G07_SC70_5  pkg SC70_5V1  page 9
  NC  = NC
  A  = PCIE_CONN_PERST_N
  GND  = SG
  Y  = BF_PCIE_PERST_N
  VCC  = XP3R3V_FPGA

(kicad_pcb
	(version 20260206)
	(generator "pcbnew")
	(generator_version "10.0")
	(general
		(thickness 1.6)
		(legacy_teardrops no)
	)
	(paper "A4")
	(title_block
		(title "timecard-production-celestica-r4006 — R4006-B0001-02_R01.brd")
		(comment 1 "Time Appliance Project (Time Card) / footprints 420-420 of 1113")
	)
	(layers
		(0 "F.Cu" signal "TOP")
		(4 "In1.Cu" signal "L02_GND1")
		(6 "In2.Cu" signal "L03_SIG1")
		(8 "In3.Cu" signal "L04_GND2")
		(10 "In4.Cu" signal "L05_VCC1")
		(12 "In5.Cu" signal "L06_VCC2")
		(14 "In6.Cu" signal "L07_GND3")
		(16 "In7.Cu" signal "L08_SIG2")
		(18 "In8.Cu" signal "L09_GND4")
		(2 "B.Cu" signal "BOTTOM")
		(9 "F.Adhes" user "F.Adhesive")
		(11 "B.Adhes" user "B.Adhesive")
		(13 "F.Paste" user "Package Geometry/Pastemask Top")
		(15 "B.Paste" user "Package Geometry/Pastemask Bottom")
		(5 "F.SilkS" user "Ref Des/Silkscreen Top")
		(7 "B.SilkS" user "Ref Des/Silkscreen Bottom")
		(1 "F.Mask" user "Board Geometry/Soldermask Top")
		(3 "B.Mask" user "Board Geometry/Soldermask Bottom")
		(17 "Dwgs.User" user "User.Drawings")
		(19 "Cmts.User" user "User.Comments")
		(21 "Eco1.User" user "User.Eco1")
		(23 "Eco2.User" user "User.Eco2")
		(25 "Edge.Cuts" user "Board Geometry/Outline")
		(27 "Margin" user)
		(31 "F.CrtYd" user "Package Geometry/Place Bound Top")
		(29 "B.CrtYd" user "Package Geometry/Place Bound Bottom")
		(35 "F.Fab" user "Ref Des/Assembly Top")
		(33 "B.Fab" user "Ref Des/Assembly Bottom")
	)
	(footprint ""
		(layer "F.Cu")
		(at 71.1454 -15.367)
		(property "Reference" "U3"
			(at -0.127 -2.11963 0)
			(unlocked yes)
			(layer "F.SilkS")
			(effects
				(font
					(size 0.7874 0.5842)
					(thickness 0.1524)
				)
			)
		)
		(property "Value" ""
			(at 0 0 0)
			(layer "F.Fab")
			(effects
				(font
					(size 1.27 1.27)
				)
			)
		)
		(property "Device Type" "74LVC1G07_SC70_5-G220-10017-01"
			(at 0.4064 2.05867 0)
			(unlocked yes)
			(layer "F.Fab")
			(hide yes)
			(effects
				(font
					(size 0.7874 0.5842)
					(thickness 0.1524)
				)
			)
		)
		(property "User Part Number" "PARTNUM*"
			(at 0.381 2.97307 0)
			(unlocked yes)
			(layer "Cmts.User")
			(hide yes)
			(effects
				(font
					(size 0.7874 0.5842)
					(thickness 0.1524)
				)
			)
		)
		(duplicate_pad_numbers_are_jumpers no)
		(fp_line
			(start -1.9304 -1.069086)
			(end -1.9304 1.069086)
			(stroke
				(width 0.1)
				(type default)
			)
			(layer "F.SilkS")
		)
		(fp_line
			(start -1.9304 1.069086)
			(end -0.952754 1.069086)
			(stroke
				(width 0.1)
				(type default)
			)
			(layer "F.SilkS")
		)
		(fp_line
			(start -0.952754 -1.32842)
			(end -0.952754 -1.069086)
			(stroke
				(width 0.1)
				(type default)
			)
			(layer "F.SilkS")
		)
		(fp_line
			(start -0.952754 -1.069086)
			(end -1.9304 -1.069086)
			(stroke
				(width 0.1)
				(type default)
			)
			(layer "F.SilkS")
		)
		(fp_line
			(start -0.952754 1.069086)
			(end -0.952754 1.32842)
			(stroke
				(width 0.1)
				(type default)
			)
			(layer "F.SilkS")
		)
		(fp_line
			(start -0.952754 1.32842)
			(end 0.952754 1.32842)
			(stroke
				(width 0.1)
				(type default)
			)
			(layer "F.SilkS")
		)
		(fp_line
			(start 0.952754 -1.32842)
			(end -0.952754 -1.32842)
			(stroke
				(width 0.1)
				(type default)
			)
			(layer "F.SilkS")
		)
		(fp_line
			(start 0.952754 -1.069086)
			(end 0.952754 -1.32842)
			(stroke
				(width 0.1)
				(type default)
			)
			(layer "F.SilkS")
		)
		(fp_line
			(start 0.952754 1.069086)
			(end 1.9304 1.069086)
			(stroke
				(width 0.1)
				(type default)
			)
			(layer "F.SilkS")
		)
		(fp_line
			(start 0.952754 1.32842)
			(end 0.952754 1.069086)
			(stroke
				(width 0.1)
				(type default)
			)
			(layer "F.SilkS")
		)
		(fp_line
			(start 1.9304 -1.069086)
			(end 0.952754 -1.069086)
			(stroke
				(width 0.1)
				(type default)
			)
			(layer "F.SilkS")
		)
		(fp_line
			(start 1.9304 1.069086)
			(end 1.9304 -1.069086)
			(stroke
				(width 0.1)
				(type default)
			)
			(layer "F.SilkS")
		)
		(fp_poly
			(pts
				(arc
					(start -2.196592 -0.75438)
					(mid -2.958592 -0.75438)
					(end -2.196592 -0.75438)
				)
			)
			(stroke
				(width 0)
				(type default)
			)
			(fill yes)
			(layer "F.SilkS")
		)
		(fp_rect
			(start -2.1844 1.58242)
			(end 2.1844 -1.58242)
			(stroke
				(width 0)
				(type default)
			)
			(fill no)
			(layer "F.CrtYd")
		)
		(fp_line
			(start -0.698754 -1.07442)
			(end 0.698754 -1.07442)
			(stroke
				(width 0.1)
				(type default)
			)
			(layer "F.Fab")
		)
		(fp_line
			(start -0.698754 -0.774954)
			(end -0.698754 -1.07442)
			(stroke
				(width 0.1)
				(type default)
			)
			(layer "F.Fab")
		)
		(fp_line
			(start -0.698754 -0.525018)
			(end -0.698754 -0.124968)
			(stroke
				(width 0.1)
				(type default)
			)
			(layer "F.Fab")
		)
		(fp_line
			(start -0.698754 0.124968)
			(end -0.698754 0.525018)
			(stroke
				(width 0.1)
				(type default)
			)
			(layer "F.Fab")
		)
		(fp_line
			(start -0.698754 0.774954)
			(end -0.698754 1.07442)
			(stroke
				(width 0.1)
				(type default)
			)
			(layer "F.Fab")
		)
		(fp_line
			(start -0.698754 1.07442)
			(end 0.698754 1.07442)
			(stroke
				(width 0.1)
				(type default)
			)
			(layer "F.Fab")
		)
		(fp_line
			(start -0.450088 1.07442)
			(end -0.450088 -1.07442)
			(stroke
				(width 0.1)
				(type default)
			)
			(layer "F.Fab")
		)
		(fp_line
			(start 0.450088 -1.07442)
			(end 0.450088 1.07442)
			(stroke
				(width 0.1)
				(type default)
			)
			(layer "F.Fab")
		)
		(fp_line
			(start 0.698754 -1.07442)
			(end 0.698754 -0.774954)
			(stroke
				(width 0.1)
				(type default)
			)
			(layer "F.Fab")
		)
		(fp_line
			(start 0.698754 -0.525018)
			(end 0.698754 0.525018)
			(stroke
				(width 0.1)
				(type default)
			)
			(layer "F.Fab")
		)
		(fp_line
			(start 0.698754 1.07442)
			(end 0.698754 0.774954)
			(stroke
				(width 0.1)
				(type default)
			)
			(layer "F.Fab")
		)
		(fp_rect
			(start -1.198626 -0.525018)
			(end -0.6985 -0.774954)
			(stroke
				(width 0)
				(type default)
			)
			(fill no)
			(layer "F.Fab")
		)
		(fp_rect
			(start -1.198626 0.124968)
			(end -0.6985 -0.124968)
			(stroke
				(width 0)
				(type default)
			)
			(fill no)
			(layer "F.Fab")
		)
		(fp_rect
			(start -1.198626 0.774954)
			(end -0.6985 0.525018)
			(stroke
				(width 0)
				(type default)
			)
			(fill no)
			(layer "F.Fab")
		)
		(fp_rect
			(start 0.6985 -0.525018)
			(end 1.198626 -0.774954)
			(stroke
				(width 0)
				(type default)
			)
			(fill no)
			(layer "F.Fab")
		)
		(fp_rect
			(start 0.6985 0.774954)
			(end 1.198626 0.525018)
			(stroke
				(width 0)
				(type default)
			)
			(fill no)
			(layer "F.Fab")
		)
		(fp_poly
			(pts
				(arc
					(start -1.942592 -0.75438)
					(mid -2.704592 -0.75438)
					(end -1.942592 -0.75438)
				)
			)
			(stroke
				(width 0)
				(type default)
			)
			(fill yes)
			(layer "F.Fab")
		)
		(fp_text user "3"
			(at -2.413 0.797306 0)
			(unlocked yes)
			(layer "F.SilkS")
			(effects
				(font
					(size 0.7874 0.5842)
					(thickness 0.1524)
				)
			)
		)
		(fp_text user "5"
			(at 2.413 -0.599948 0)
			(unlocked yes)
			(layer "F.SilkS")
			(effects
				(font
					(size 0.7874 0.5842)
					(thickness 0.1524)
				)
			)
		)
		(fp_text user "4"
			(at 2.442972 0.7747 0)
			(unlocked yes)
			(layer "F.SilkS")
			(effects
				(font
					(size 0.7874 0.5842)
					(thickness 0.1524)
				)
			)
		)
		(fp_text user "3"
			(at -2.159 0.797306 0)
			(unlocked yes)
			(layer "F.Fab")
			(effects
				(font
					(size 0.7874 0.5842)
					(thickness 0.1524)
				)
			)
		)
		(fp_text user "5"
			(at 2.159 -0.599948 0)
			(unlocked yes)
			(layer "F.Fab")
			(effects
				(font
					(size 0.7874 0.5842)
					(thickness 0.1524)
				)
			)
		)
		(fp_text user "4"
			(at 2.188972 0.7747 0)
			(unlocked yes)
			(layer "F.Fab")
			(effects
				(font
					(size 0.7874 0.5842)
					(thickness 0.1524)
				)
			)
		)
		(pad "1" smd rect
			(at -1.1938 -0.649986 90)
			(size 0.3302 0.9652)
			(layers "F.Cu" "F.Mask" "F.Paste")
			(net "Net_761")
		)
		(pad "2" smd rect
			(at -1.1938 0 90)
			(size 0.3302 0.9652)
			(layers "F.Cu" "F.Mask" "F.Paste")
			(net "PCIE_CONN_PERST_N")
		)
		(pad "3" smd rect
			(at -1.1938 0.649986 90)
			(size 0.3302 0.9652)
			(layers "F.Cu" "F.Mask" "F.Paste")
			(net "SG")
		)
		(pad "4" smd rect
			(at 1.1938 0.649986 90)
			(size 0.3302 0.9652)
			(layers "F.Cu" "F.Mask" "F.Paste")
			(net "BF_PCIE_PERST_N")
		)
		(pad "5" smd rect
			(at 1.1938 -0.649986 90)
			(size 0.3302 0.9652)
			(layers "F.Cu" "F.Mask" "F.Paste")
			(net "XP3R3V_FPGA")
		)
		(zone
			(layer "F.Cu")
			(hatch none 0.5)
			(connect_pads
				(clearance 0)
			)
			(min_thickness 0.25)
			(keepout
				(tracks allowed)
				(vias not_allowed)
				(pads allowed)
				(copperpour not_allowed)
				(footprints allowed)
			)
			(placement
				(enabled no)
				(sheetname "")
			)
			(fill
				(thermal_gap 0.5)
				(thermal_bridge_width 0.5)
				(island_removal_mode 0)
			)
			(polygon
				(pts
					(xy 70.5104 -14.3637) (xy 71.7804 -14.3637) (xy 71.7804 -16.3703) (xy 70.5104 -16.3703)
				)
			)
		)
	)
)
